# S9S_MB_2U (Grand Teton) — schematic netlist excerpt (pin names and nets, part order shuffled) for the footprints in the layout excerpt that follows; sources: Cadence DE-HDL packaged netlist, KiCad conversion of 03242023_DA0F0TMBIJ0_F0T_Motherboard_J_brd_V01_OCP.brd

J110  CONN112_10137002101LF  CONN112_10137002-101LF IO  pkg HSD_F112D8_P2W1-2_RDH  page 141
  A1  = GPU_FPGA_EROT_RECOV_BUF_N
  A2  = GND
  A3  = GPU_HMC_PRSNT_N
  A4  = GND
  A5  = GPU_BASE_HMC_READY
  A6  = GND
  A7  = GPU_BASE_STBY_EN_BUF
  A8  = GND
  B1  = GND
  B2  = P5E_CPU1_PE3_RX_DP<14>
  B3  = GND
  B4  = P5E_CPU1_PE3_RX_DP<12>
  B5  = GND
  B6  = P5E_CPU1_PE3_RX_DN<10>
  B7  = GND
  B8  = P5E_CPU1_PE3_RX_DN<8>
  C1  = P5E_CPU1_PE3_RX_DP<15>
  C2  = P5E_CPU1_PE3_RX_DN<14>
  C3  = P5E_CPU1_PE3_RX_DP<13>
  C4  = P5E_CPU1_PE3_RX_DN<12>
  C5  = P5E_CPU1_PE3_RX_DN<11>
  C6  = P5E_CPU1_PE3_RX_DP<10>
  C7  = P5E_CPU1_PE3_RX_DN<9>
  C8  = P5E_CPU1_PE3_RX_DP<8>
  D1  = P5E_CPU1_PE3_RX_DN<15>
  D2  = GND
  D3  = P5E_CPU1_PE3_RX_DN<13>
  D4  = GND
  D5  = P5E_CPU1_PE3_RX_DP<11>
  D6  = GND
  D7  = P5E_CPU1_PE3_RX_DP<9>
  D8  = GND
  E1  = GND
  E2  = P5E_CPU1_PE2_RX_DP<14>
  E3  = GND
  E4  = P5E_CPU1_PE2_RX_DP<12>
  E5  = GND
  E6  = P5E_CPU1_PE2_RX_DP<10>
  E7  = GND
  E8  = P5E_CPU1_PE2_RX_DP<8>
  F1  = P5E_CPU1_PE2_RX_DP<15>
  F2  = P5E_CPU1_PE2_RX_DN<14>
  F3  = P5E_CPU1_PE2_RX_DP<13>
  F4  = P5E_CPU1_PE2_RX_DN<12>
  F5  = P5E_CPU1_PE2_RX_DP<11>
  F6  = P5E_CPU1_PE2_RX_DN<10>
  F7  = P5E_CPU1_PE2_RX_DP<9>
  F8  = P5E_CPU1_PE2_RX_DN<8>
  G1  = P5E_CPU1_PE2_RX_DN<15>
  G2  = GND
  G3  = P5E_CPU1_PE2_RX_DN<13>
  G4  = GND
  G5  = P5E_CPU1_PE2_RX_DN<11>
  G6  = GND
  G7  = P5E_CPU1_PE2_RX_DN<9>
  G8  = GND
  H1  = GND
  H2  = P5E_CPU1_PE3_TX_C_DN<14>
  H3  = GND
  H4  = P5E_CPU1_PE3_TX_C_DN<12>
  H5  = GND
  H6  = P5E_CPU1_PE3_TX_C_DN<10>
  H7  = GND
  H8  = P5E_CPU1_PE3_TX_C_DN<8>
  I1  = P5E_CPU1_PE3_TX_C_DN<15>
  I2  = P5E_CPU1_PE3_TX_C_DP<14>
  I3  = P5E_CPU1_PE3_TX_C_DN<13>
  I4  = P5E_CPU1_PE3_TX_C_DP<12>
  I5  = P5E_CPU1_PE3_TX_C_DN<11>
  I6  = P5E_CPU1_PE3_TX_C_DP<10>
  I7  = P5E_CPU1_PE3_TX_C_DN<9>
  I8  = P5E_CPU1_PE3_TX_C_DP<8>
  J1  = P5E_CPU1_PE3_TX_C_DP<15>
  J2  = GND
  J3  = P5E_CPU1_PE3_TX_C_DP<13>
  J4  = GND
  J5  = P5E_CPU1_PE3_TX_C_DP<11>
  J6  = GND
  J7  = P5E_CPU1_PE3_TX_C_DP<9>
  J8  = GND
  K1  = GND
  K2  = P5E_CPU1_PE2_TX_C_DP<14>
  K3  = GND
  K4  = P5E_CPU1_PE2_TX_C_DP<12>
  K5  = GND
  K6  = P5E_CPU1_PE2_TX_C_DP<10>
  K7  = GND
  K8  = P5E_CPU1_PE2_TX_C_DP<8>
  L1  = P5E_CPU1_PE2_TX_C_DP<15>
  L2  = P5E_CPU1_PE2_TX_C_DN<14>
  L3  = P5E_CPU1_PE2_TX_C_DP<13>
  L4  = P5E_CPU1_PE2_TX_C_DN<12>
  L5  = P5E_CPU1_PE2_TX_C_DP<11>
  L6  = P5E_CPU1_PE2_TX_C_DN<10>
  L7  = P5E_CPU1_PE2_TX_C_DP<9>
  L8  = P5E_CPU1_PE2_TX_C_DN<8>
  M1  = P5E_CPU1_PE2_TX_C_DN<15>
  M2  = GND
  M3  = P5E_CPU1_PE2_TX_C_DN<13>
  M4  = GND
  M5  = P5E_CPU1_PE2_TX_C_DN<11>
  M6  = GND
  M7  = P5E_CPU1_PE2_TX_C_DN<9>
  M8  = GND
  N1  = GND
  N2  = GPU_FPGA_BOOT_EN_BUF
  N3  = GND
  N4  = FM_SMB_1_ALERT_GPU_N
  N5  = GND
  N6  = FM_SMB_2_ALERT_GPU_N
  N7  = GND
  N8  = GPU_FPGA_EROT_RST_BUF_N

(kicad_pcb
	(version 20260206)
	(generator "pcbnew")
	(generator_version "10.0")
	(general
		(thickness 1.6)
		(legacy_teardrops no)
	)
	(paper "A4")
	(title_block
		(title "03242023_DA0F0TMBIJ0_F0T_Motherboard_J_brd_V01_OCP.brd")
		(comment 1 "Grand Teton / footprint 1392 of 6105 (J110), pads 32-48 of 48")
	)
	(layers
		(0 "F.Cu" signal "TOP")
		(4 "In1.Cu" signal "GND")
		(6 "In2.Cu" signal "IN1")
		(8 "In3.Cu" signal "GND1")
		(10 "In4.Cu" signal "IN2")
		(12 "In5.Cu" signal "GND2")
		(14 "In6.Cu" signal "IN3")
		(16 "In7.Cu" signal "GND3")
		(18 "In8.Cu" signal "VCC")
		(20 "In9.Cu" signal "VCC1")
		(22 "In10.Cu" signal "GND4")
		(24 "In11.Cu" signal "IN4")
		(26 "In12.Cu" signal "GND5")
		(28 "In13.Cu" signal "IN5")
		(30 "In14.Cu" signal "GND6")
		(32 "In15.Cu" signal "IN6")
		(34 "In16.Cu" signal "GND7")
		(2 "B.Cu" signal "BOTTOM")
		(9 "F.Adhes" user "F.Adhesive")
		(11 "B.Adhes" user "B.Adhesive")
		(13 "F.Paste" user "Package Geometry/Pastemask Top")
		(15 "B.Paste" user "Package Geometry/Pastemask Bottom")
		(5 "F.SilkS" user "Ref Des/Silkscreen Top")
		(7 "B.SilkS" user "Ref Des/Silkscreen Bottom")
		(1 "F.Mask" user "Board Geometry/Soldermask Top")
		(3 "B.Mask" user "Board Geometry/Soldermask Bottom")
		(17 "Dwgs.User" user "User.Drawings")
		(19 "Cmts.User" user "User.Comments")
		(21 "Eco1.User" user "User.Eco1")
		(23 "Eco2.User" user "User.Eco2")
		(25 "Edge.Cuts" user "Board Geometry/Outline")
		(27 "Margin" user)
		(31 "F.CrtYd" user "Package Geometry/Place Bound Top")
		(29 "B.CrtYd" user "Package Geometry/Place Bound Bottom")
		(35 "F.Fab" user "Ref Des/Assembly Top")
		(33 "B.Fab" user "Ref Des/Assembly Bottom")
	)
	(footprint ""
		(layer "F.Cu")
		(at 125.750066 -440.489848)
		(property "Reference" "J110"
			(at -3.723386 20.59559 0)
			(unlocked yes)
			(layer "F.SilkS")
			(effects
				(font
					(size 0.7874 0.5842)
					(thickness 0.1524)
				)
				(justify left)
			)
		)
		(property "Value" ""
			(at 0 0 0)
			(layer "F.Fab")
			(effects
				(font
					(size 1.27 1.27)
				)
			)
		)
		(duplicate_pad_numbers_are_jumpers no)
		(pad "J8" thru_hole circle
			(at 13.999972 10.999978 180)
			(size 0.906272 0.906272)
			(drill 0.499872)
			(layers "*.Cu" "*.Mask")
			(remove_unused_layers no)
			(net "GND")
			(clearance 0.0508)
			(thermal_gap 0.0508)
		)
		(pad "K1" thru_hole circle
			(at 0 11.999976 180)
			(size 0.906272 0.906272)
			(drill 0.499872)
			(layers "*.Cu" "*.Mask")
			(remove_unused_layers no)
			(net "GND")
			(clearance 0.0508)
			(thermal_gap 0.0508)
		)
		(pad "K3" thru_hole circle
			(at 3.999992 11.999976 180)
			(size 0.906272 0.906272)
			(drill 0.499872)
			(layers "*.Cu" "*.Mask")
			(remove_unused_layers no)
			(net "GND")
			(clearance 0.0508)
			(thermal_gap 0.0508)
		)
		(pad "K5" thru_hole circle
			(at 7.999984 11.999976 180)
			(size 0.906272 0.906272)
			(drill 0.499872)
			(layers "*.Cu" "*.Mask")
			(remove_unused_layers no)
			(net "GND")
			(clearance 0.0508)
			(thermal_gap 0.0508)
		)
		(pad "K7" thru_hole circle
			(at 11.999976 11.999976 180)
			(size 0.906272 0.906272)
			(drill 0.499872)
			(layers "*.Cu" "*.Mask")
			(remove_unused_layers no)
			(net "GND")
			(clearance 0.0508)
			(thermal_gap 0.0508)
		)
		(pad "M2" thru_hole circle
			(at 1.999996 14.59992 180)
			(size 0.906272 0.906272)
			(drill 0.499872)
			(layers "*.Cu" "*.Mask")
			(remove_unused_layers no)
			(net "GND")
			(clearance 0.0508)
			(thermal_gap 0.0508)
		)
		(pad "M4" thru_hole circle
			(at 5.999988 14.59992 180)
			(size 0.906272 0.906272)
			(drill 0.499872)
			(layers "*.Cu" "*.Mask")
			(remove_unused_layers no)
			(net "GND")
			(clearance 0.0508)
			(thermal_gap 0.0508)
		)
		(pad "M6" thru_hole circle
			(at 9.99998 14.59992 180)
			(size 0.906272 0.906272)
			(drill 0.499872)
			(layers "*.Cu" "*.Mask")
			(remove_unused_layers no)
			(net "GND")
			(clearance 0.0508)
			(thermal_gap 0.0508)
		)
		(pad "M8" thru_hole circle
			(at 13.999972 14.59992 180)
			(size 0.906272 0.906272)
			(drill 0.499872)
			(layers "*.Cu" "*.Mask")
			(remove_unused_layers no)
			(net "GND")
			(clearance 0.0508)
			(thermal_gap 0.0508)
		)
		(pad "N1" thru_hole circle
			(at 0 15.599918 180)
			(size 0.906272 0.906272)
			(drill 0.499872)
			(layers "*.Cu" "*.Mask")
			(remove_unused_layers no)
			(net "GND")
			(clearance 0.0508)
			(thermal_gap 0.0508)
		)
		(pad "N2" thru_hole circle
			(at 1.999996 15.80007 180)
			(size 0.766318 0.766318)
			(drill 0.359918)
			(layers "*.Cu" "*.Mask")
			(remove_unused_layers no)
			(net "GPU_FPGA_BOOT_EN_BUF")
			(clearance 0.0508)
			(thermal_gap 0.0508)
		)
		(pad "N3" thru_hole circle
			(at 3.999992 15.599918 180)
			(size 0.906272 0.906272)
			(drill 0.499872)
			(layers "*.Cu" "*.Mask")
			(remove_unused_layers no)
			(net "GND")
			(clearance 0.0508)
			(thermal_gap 0.0508)
		)
		(pad "N4" thru_hole circle
			(at 5.999988 15.80007 180)
			(size 0.766318 0.766318)
			(drill 0.359918)
			(layers "*.Cu" "*.Mask")
			(remove_unused_layers no)
			(net "FM_SMB_1_ALERT_GPU_N")
			(clearance 0.0508)
			(thermal_gap 0.0508)
		)
		(pad "N5" thru_hole circle
			(at 7.999984 15.599918 180)
			(size 0.906272 0.906272)
			(drill 0.499872)
			(layers "*.Cu" "*.Mask")
			(remove_unused_layers no)
			(net "GND")
			(clearance 0.0508)
			(thermal_gap 0.0508)
		)
		(pad "N6" thru_hole circle
			(at 9.99998 15.80007 180)
			(size 0.766318 0.766318)
			(drill 0.359918)
			(layers "*.Cu" "*.Mask")
			(remove_unused_layers no)
			(net "FM_SMB_2_ALERT_GPU_N")
			(clearance 0.0508)
			(thermal_gap 0.0508)
		)
		(pad "N7" thru_hole circle
			(at 11.999976 15.599918 180)
			(size 0.906272 0.906272)
			(drill 0.499872)
			(layers "*.Cu" "*.Mask")
			(remove_unused_layers no)
			(net "GND")
			(clearance 0.0508)
			(thermal_gap 0.0508)
		)
		(pad "N8" thru_hole circle
			(at 13.999972 15.80007 180)
			(size 0.766318 0.766318)
			(drill 0.359918)
			(layers "*.Cu" "*.Mask")
			(remove_unused_layers no)
			(net "GPU_FPGA_EROT_RST_BUF_N")
			(clearance 0.0508)
			(thermal_gap 0.0508)
		)
	)
)
